# TIMECARD (Time Appliance Project (Time Card)) — schematic netlist excerpt (pin names and nets, part order shuffled) for the footprints in the layout excerpt that follows; sources: Cadence DE-HDL packaged netlist, KiCad conversion of R4006-B0001-02_R01.brd

R147  RESISTOR  10KOHM 1%  pkg SMC_0402R_H016  page 16 : \1\ = XP3R3V_FPGA ; \2\ = R_PCA9546_I2C_SDA
C273  CAPACITOR  0.1UF 10V 10%  pkg SMC_0402R_H022  page 22 : \1\ = XP3R3V_GPS ; \2\ = SG

(kicad_pcb
	(version 20260206)
	(generator "pcbnew")
	(generator_version "10.0")
	(general
		(thickness 1.6)
		(legacy_teardrops no)
	)
	(paper "A4")
	(title_block
		(title "timecard-production-celestica-r4006 — R4006-B0001-02_R01.brd")
		(comment 1 "Time Appliance Project (Time Card) / footprints 1035-1036 of 1113")
	)
	(layers
		(0 "F.Cu" signal "TOP")
		(4 "In1.Cu" signal "L02_GND1")
		(6 "In2.Cu" signal "L03_SIG1")
		(8 "In3.Cu" signal "L04_GND2")
		(10 "In4.Cu" signal "L05_VCC1")
		(12 "In5.Cu" signal "L06_VCC2")
		(14 "In6.Cu" signal "L07_GND3")
		(16 "In7.Cu" signal "L08_SIG2")
		(18 "In8.Cu" signal "L09_GND4")
		(2 "B.Cu" signal "BOTTOM")
		(9 "F.Adhes" user "F.Adhesive")
		(11 "B.Adhes" user "B.Adhesive")
		(13 "F.Paste" user "Package Geometry/Pastemask Top")
		(15 "B.Paste" user "Package Geometry/Pastemask Bottom")
		(5 "F.SilkS" user "Ref Des/Silkscreen Top")
		(7 "B.SilkS" user "Ref Des/Silkscreen Bottom")
		(1 "F.Mask" user "Board Geometry/Soldermask Top")
		(3 "B.Mask" user "Board Geometry/Soldermask Bottom")
		(17 "Dwgs.User" user "User.Drawings")
		(19 "Cmts.User" user "User.Comments")
		(21 "Eco1.User" user "User.Eco1")
		(23 "Eco2.User" user "User.Eco2")
		(25 "Edge.Cuts" user "Board Geometry/Outline")
		(27 "Margin" user)
		(31 "F.CrtYd" user "Package Geometry/Place Bound Top")
		(29 "B.CrtYd" user "Package Geometry/Place Bound Bottom")
		(35 "F.Fab" user "Ref Des/Assembly Top")
		(33 "B.Fab" user "Ref Des/Assembly Bottom")
	)
	(footprint ""
		(layer "B.Cu")
		(at 117.729 -100.076)
		(property "Reference" "C273"
			(at -1.397 -1.48463 0)
			(unlocked yes)
			(layer "B.SilkS")
			(effects
				(font
					(size 0.7874 0.5842)
					(thickness 0.1524)
				)
				(justify mirror)
			)
		)
		(property "Value" "VAL*"
			(at -0.0762 2.067306 0)
			(unlocked yes)
			(layer "B.Fab")
			(hide yes)
			(effects
				(font
					(size 0.7874 0.5842)
					(thickness 0.1524)
				)
				(justify mirror)
			)
		)
		(property "Tolerance" "TOL*"
			(at -0.0762 3.032506 0)
			(unlocked yes)
			(layer "Cmts.User")
			(hide yes)
			(effects
				(font
					(size 0.7874 0.5842)
					(thickness 0.1524)
				)
				(justify mirror)
			)
		)
		(property "User Part Number" "PARTNUM*"
			(at -0.1016 4.023106 0)
			(unlocked yes)
			(layer "Cmts.User")
			(hide yes)
			(effects
				(font
					(size 0.7874 0.5842)
					(thickness 0.1524)
				)
				(justify mirror)
			)
		)
		(property "Device Type" "CAPACITOR-G105-0B104-CK,0.1UF,A"
			(at -0.0508 1.127506 0)
			(unlocked yes)
			(layer "B.Fab")
			(hide yes)
			(effects
				(font
					(size 0.7874 0.5842)
					(thickness 0.1524)
				)
				(justify mirror)
			)
		)
		(duplicate_pad_numbers_are_jumpers no)
		(fp_line
			(start -1.143 -0.5588)
			(end 1.143 -0.5588)
			(stroke
				(width 0.1)
				(type default)
			)
			(layer "B.SilkS")
		)
		(fp_line
			(start -1.143 0.5588)
			(end -1.143 -0.5588)
			(stroke
				(width 0.1)
				(type default)
			)
			(layer "B.SilkS")
		)
		(fp_line
			(start 1.143 -0.5588)
			(end 1.143 0.5588)
			(stroke
				(width 0.1)
				(type default)
			)
			(layer "B.SilkS")
		)
		(fp_line
			(start 1.143 0.5588)
			(end -1.143 0.5588)
			(stroke
				(width 0.1)
				(type default)
			)
			(layer "B.SilkS")
		)
		(fp_rect
			(start -1.143 -0.5588)
			(end 1.143 0.5588)
			(stroke
				(width 0)
				(type default)
			)
			(fill no)
			(layer "B.CrtYd")
		)
		(fp_line
			(start -0.508 -0.3048)
			(end 0.508 -0.3048)
			(stroke
				(width 0.1)
				(type default)
			)
			(layer "B.Fab")
		)
		(fp_line
			(start -0.508 0.3048)
			(end -0.508 -0.3048)
			(stroke
				(width 0.1)
				(type default)
			)
			(layer "B.Fab")
		)
		(fp_line
			(start 0.508 -0.3048)
			(end 0.508 0.3048)
			(stroke
				(width 0.1)
				(type default)
			)
			(layer "B.Fab")
		)
		(fp_line
			(start 0.508 0.3048)
			(end -0.508 0.3048)
			(stroke
				(width 0.1)
				(type default)
			)
			(layer "B.Fab")
		)
		(pad "1" smd rect
			(at 0.5334 0 180)
			(size 0.7112 0.6096)
			(layers "B.Cu" "B.Mask" "B.Paste")
			(net "XP3R3V_GPS")
		)
		(pad "2" smd rect
			(at -0.5334 0 180)
			(size 0.7112 0.6096)
			(layers "B.Cu" "B.Mask" "B.Paste")
			(net "SG")
		)
		(zone
			(layer "B.Cu")
			(hatch none 0.5)
			(connect_pads
				(clearance 0)
			)
			(min_thickness 0.25)
			(keepout
				(tracks allowed)
				(vias not_allowed)
				(pads allowed)
				(copperpour not_allowed)
				(footprints allowed)
			)
			(placement
				(enabled no)
				(sheetname "")
			)
			(fill
				(thermal_gap 0.5)
				(thermal_bridge_width 0.5)
				(island_removal_mode 0)
			)
			(polygon
				(pts
					(xy 117.6528 -100.3808) (xy 117.6528 -99.7712) (xy 117.8052 -99.7712) (xy 117.8052 -100.3808)
				)
			)
		)
	)
	(footprint ""
		(layer "B.Cu")
		(at 21.0566 -41.6306)
		(property "Reference" "R147"
			(at -0.3556 4.83997 0)
			(unlocked yes)
			(layer "B.SilkS")
			(effects
				(font
					(size 0.7874 0.5842)
					(thickness 0.1524)
				)
				(justify mirror)
			)
		)
		(property "Value" "VAL*"
			(at -0.02032 2.13233 0)
			(unlocked yes)
			(layer "B.Fab")
			(hide yes)
			(effects
				(font
					(size 0.7874 0.5842)
					(thickness 0.1524)
				)
				(justify mirror)
			)
		)
		(property "Device Type" "RESISTOR-G155-11002-01,10KOHM,A"
			(at -0.008382 1.210564 0)
			(unlocked yes)
			(layer "B.Fab")
			(hide yes)
			(effects
				(font
					(size 0.7874 0.5842)
					(thickness 0.1524)
				)
				(justify mirror)
			)
		)
		(property "User Part Number" "PARTNUM*"
			(at -0.02032 4.024884 0)
			(unlocked yes)
			(layer "Cmts.User")
			(hide yes)
			(effects
				(font
					(size 0.7874 0.5842)
					(thickness 0.1524)
				)
				(justify mirror)
			)
		)
		(property "Tolerance" "TOL*"
			(at -0.044704 3.05435 0)
			(unlocked yes)
			(layer "Cmts.User")
			(hide yes)
			(effects
				(font
					(size 0.7874 0.5842)
					(thickness 0.1524)
				)
				(justify mirror)
			)
		)
		(duplicate_pad_numbers_are_jumpers no)
		(fp_line
			(start -1.143 -0.5588)
			(end 1.143 -0.5588)
			(stroke
				(width 0.1)
				(type default)
			)
			(layer "B.SilkS")
		)
		(fp_line
			(start -1.143 0.5588)
			(end -1.143 -0.5588)
			(stroke
				(width 0.1)
				(type default)
			)
			(layer "B.SilkS")
		)
		(fp_line
			(start 1.143 -0.5588)
			(end 1.143 0.5588)
			(stroke
				(width 0.1)
				(type default)
			)
			(layer "B.SilkS")
		)
		(fp_line
			(start 1.143 0.5588)
			(end -1.143 0.5588)
			(stroke
				(width 0.1)
				(type default)
			)
			(layer "B.SilkS")
		)
		(fp_rect
			(start 1.143 0.5588)
			(end -1.143 -0.5588)
			(stroke
				(width 0)
				(type default)
			)
			(fill no)
			(layer "B.CrtYd")
		)
		(fp_line
			(start -0.508 -0.3048)
			(end 0.508 -0.3048)
			(stroke
				(width 0.1)
				(type default)
			)
			(layer "B.Fab")
		)
		(fp_line
			(start -0.508 0.3048)
			(end -0.508 -0.3048)
			(stroke
				(width 0.1)
				(type default)
			)
			(layer "B.Fab")
		)
		(fp_line
			(start 0.508 -0.3048)
			(end 0.508 0.3048)
			(stroke
				(width 0.1)
				(type default)
			)
			(layer "B.Fab")
		)
		(fp_line
			(start 0.508 0.3048)
			(end -0.508 0.3048)
			(stroke
				(width 0.1)
				(type default)
			)
			(layer "B.Fab")
		)
		(pad "1" smd rect
			(at 0.5334 0 180)
			(size 0.7112 0.6096)
			(layers "B.Cu" "B.Mask" "B.Paste")
			(net "XP3R3V_FPGA")
		)
		(pad "2" smd rect
			(at -0.5334 0 180)
			(size 0.7112 0.6096)
			(layers "B.Cu" "B.Mask" "B.Paste")
			(net "R_PCA9546_I2C_SDA")
		)
		(zone
			(layer "B.Cu")
			(hatch none 0.5)
			(connect_pads
				(clearance 0)
			)
			(min_thickness 0.25)
			(keepout
				(tracks allowed)
				(vias not_allowed)
				(pads allowed)
				(copperpour not_allowed)
				(footprints allowed)
			)
			(placement
				(enabled no)
				(sheetname "")
			)
			(fill
				(thermal_gap 0.5)
				(thermal_bridge_width 0.5)
				(island_removal_mode 0)
			)
			(polygon
				(pts
					(xy 21.1328 -41.3258) (xy 21.1328 -41.9354) (xy 20.9804 -41.9354) (xy 20.9804 -41.3258)
				)
			)
		)
	)
)
